# S9S_MB_2U (Grand Teton) — schematic netlist excerpt (pin names and nets, part order shuffled) for the footprints in the layout excerpt that follows; sources: Cadence DE-HDL packaged netlist, KiCad conversion of 03242023_DA0F0TMBIJ0_F0T_Motherboard_J_brd_V01_OCP.brd

R2133  Q_RES  1K 1% CHIP  pkg 0402LF  page 201 : A = P3V3_AUX ; B = PU_ESPI_ENABLE_STRAP
C222  Q_CAP  10UF 6.3V 20% X6S  pkg C0402  page 77 : A = PVCCIN_CPU1 ; B = GND

(kicad_pcb
	(version 20260206)
	(generator "pcbnew")
	(generator_version "10.0")
	(general
		(thickness 1.6)
		(legacy_teardrops no)
	)
	(paper "A4")
	(title_block
		(title "03242023_DA0F0TMBIJ0_F0T_Motherboard_J_brd_V01_OCP.brd")
		(comment 1 "Grand Teton / footprints 863-864 of 6105")
	)
	(layers
		(0 "F.Cu" signal "TOP")
		(4 "In1.Cu" signal "GND")
		(6 "In2.Cu" signal "IN1")
		(8 "In3.Cu" signal "GND1")
		(10 "In4.Cu" signal "IN2")
		(12 "In5.Cu" signal "GND2")
		(14 "In6.Cu" signal "IN3")
		(16 "In7.Cu" signal "GND3")
		(18 "In8.Cu" signal "VCC")
		(20 "In9.Cu" signal "VCC1")
		(22 "In10.Cu" signal "GND4")
		(24 "In11.Cu" signal "IN4")
		(26 "In12.Cu" signal "GND5")
		(28 "In13.Cu" signal "IN5")
		(30 "In14.Cu" signal "GND6")
		(32 "In15.Cu" signal "IN6")
		(34 "In16.Cu" signal "GND7")
		(2 "B.Cu" signal "BOTTOM")
		(9 "F.Adhes" user "F.Adhesive")
		(11 "B.Adhes" user "B.Adhesive")
		(13 "F.Paste" user "Package Geometry/Pastemask Top")
		(15 "B.Paste" user "Package Geometry/Pastemask Bottom")
		(5 "F.SilkS" user "Ref Des/Silkscreen Top")
		(7 "B.SilkS" user "Ref Des/Silkscreen Bottom")
		(1 "F.Mask" user "Board Geometry/Soldermask Top")
		(3 "B.Mask" user "Board Geometry/Soldermask Bottom")
		(17 "Dwgs.User" user "User.Drawings")
		(19 "Cmts.User" user "User.Comments")
		(21 "Eco1.User" user "User.Eco1")
		(23 "Eco2.User" user "User.Eco2")
		(25 "Edge.Cuts" user "Board Geometry/Outline")
		(27 "Margin" user)
		(31 "F.CrtYd" user "Package Geometry/Place Bound Top")
		(29 "B.CrtYd" user "Package Geometry/Place Bound Bottom")
		(35 "F.Fab" user "Ref Des/Assembly Top")
		(33 "B.Fab" user "Ref Des/Assembly Bottom")
	)
	(footprint ""
		(layer "F.Cu")
		(at 105.315004 -247.715278 90)
		(property "Reference" "C222"
			(at 0 0 90)
			(layer "F.SilkS")
			(hide yes)
			(effects
				(font
					(size 1.27 1.27)
				)
			)
		)
		(property "Value" ""
			(at 0 0 90)
			(layer "F.Fab")
			(effects
				(font
					(size 1.27 1.27)
				)
			)
		)
		(duplicate_pad_numbers_are_jumpers no)
		(fp_line
			(start 0.7874 -0.4064)
			(end 0.7874 0.4064)
			(stroke
				(width 0.1524)
				(type default)
			)
			(layer "F.SilkS")
		)
		(fp_line
			(start -0.7874 -0.4064)
			(end 0.7874 -0.4064)
			(stroke
				(width 0.1524)
				(type default)
			)
			(layer "F.SilkS")
		)
		(fp_line
			(start 0.7874 0.4064)
			(end -0.7874 0.4064)
			(stroke
				(width 0.1524)
				(type default)
			)
			(layer "F.SilkS")
		)
		(fp_line
			(start -0.7874 0.4064)
			(end -0.7874 -0.4064)
			(stroke
				(width 0.1524)
				(type default)
			)
			(layer "F.SilkS")
		)
		(fp_line
			(start -0.12065 -0.305054)
			(end -0.12065 -0.2794)
			(stroke
				(width 0.1)
				(type default)
			)
			(layer "F.Fab")
		)
		(fp_line
			(start -0.67945 -0.305054)
			(end -0.12065 -0.305054)
			(stroke
				(width 0.1)
				(type default)
			)
			(layer "F.Fab")
		)
		(fp_line
			(start 0.67945 -0.3048)
			(end 0.67945 0.3048)
			(stroke
				(width 0.1)
				(type default)
			)
			(layer "F.Fab")
		)
		(fp_line
			(start 0.12065 -0.3048)
			(end 0.67945 -0.3048)
			(stroke
				(width 0.1)
				(type default)
			)
			(layer "F.Fab")
		)
		(fp_line
			(start 0.12065 -0.2794)
			(end 0.12065 -0.3048)
			(stroke
				(width 0.1)
				(type default)
			)
			(layer "F.Fab")
		)
		(fp_line
			(start -0.12065 -0.2794)
			(end 0.12065 -0.2794)
			(stroke
				(width 0.1)
				(type default)
			)
			(layer "F.Fab")
		)
		(fp_line
			(start 0.120396 0.2794)
			(end -0.12065 0.2794)
			(stroke
				(width 0.1)
				(type default)
			)
			(layer "F.Fab")
		)
		(fp_line
			(start -0.12065 0.2794)
			(end -0.12065 0.3048)
			(stroke
				(width 0.1)
				(type default)
			)
			(layer "F.Fab")
		)
		(fp_line
			(start 0.67945 0.3048)
			(end 0.120396 0.3048)
			(stroke
				(width 0.1)
				(type default)
			)
			(layer "F.Fab")
		)
		(fp_line
			(start 0.120396 0.3048)
			(end 0.120396 0.2794)
			(stroke
				(width 0.1)
				(type default)
			)
			(layer "F.Fab")
		)
		(fp_line
			(start -0.12065 0.3048)
			(end -0.67945 0.3048)
			(stroke
				(width 0.1)
				(type default)
			)
			(layer "F.Fab")
		)
		(fp_line
			(start -0.67945 0.3048)
			(end -0.67945 -0.305054)
			(stroke
				(width 0.1)
				(type default)
			)
			(layer "F.Fab")
		)
		(pad "1" smd circle
			(at -0.40005 0 90)
			(size 0 0)
			(layers "F.Cu" "F.Mask" "F.Paste")
			(net "PVCCIN_CPU1")
		)
		(pad "2" smd circle
			(at 0.40005 0 90)
			(size 0 0)
			(layers "F.Cu" "F.Mask" "F.Paste")
			(net "GND")
		)
	)
	(footprint ""
		(layer "F.Cu")
		(at 435.17312 -43.262804 180)
		(property "Reference" "R2133"
			(at 0 0 180)
			(layer "F.SilkS")
			(hide yes)
			(effects
				(font
					(size 1.27 1.27)
				)
			)
		)
		(property "Value" ""
			(at 0 0 180)
			(layer "F.Fab")
			(effects
				(font
					(size 1.27 1.27)
				)
			)
		)
		(duplicate_pad_numbers_are_jumpers no)
		(fp_line
			(start 0.7874 0.4064)
			(end -0.7874 0.4064)
			(stroke
				(width 0.1524)
				(type default)
			)
			(layer "F.SilkS")
		)
		(fp_line
			(start 0.7874 -0.4064)
			(end 0.7874 0.4064)
			(stroke
				(width 0.1524)
				(type default)
			)
			(layer "F.SilkS")
		)
		(fp_line
			(start -0.7874 0.4064)
			(end -0.7874 -0.4064)
			(stroke
				(width 0.1524)
				(type default)
			)
			(layer "F.SilkS")
		)
		(fp_line
			(start -0.7874 -0.4064)
			(end 0.7874 -0.4064)
			(stroke
				(width 0.1524)
				(type default)
			)
			(layer "F.SilkS")
		)
		(fp_line
			(start 0.67945 0.3048)
			(end 0.120396 0.3048)
			(stroke
				(width 0.1)
				(type default)
			)
			(layer "F.Fab")
		)
		(fp_line
			(start 0.67945 -0.3048)
			(end 0.67945 0.3048)
			(stroke
				(width 0.1)
				(type default)
			)
			(layer "F.Fab")
		)
		(fp_line
			(start 0.12065 -0.2794)
			(end 0.12065 -0.3048)
			(stroke
				(width 0.1)
				(type default)
			)
			(layer "F.Fab")
		)
		(fp_line
			(start 0.12065 -0.3048)
			(end 0.67945 -0.3048)
			(stroke
				(width 0.1)
				(type default)
			)
			(layer "F.Fab")
		)
		(fp_line
			(start 0.120396 0.3048)
			(end 0.120396 0.2794)
			(stroke
				(width 0.1)
				(type default)
			)
			(layer "F.Fab")
		)
		(fp_line
			(start 0.120396 0.2794)
			(end -0.12065 0.2794)
			(stroke
				(width 0.1)
				(type default)
			)
			(layer "F.Fab")
		)
		(fp_line
			(start -0.12065 0.3048)
			(end -0.67945 0.3048)
			(stroke
				(width 0.1)
				(type default)
			)
			(layer "F.Fab")
		)
		(fp_line
			(start -0.12065 0.2794)
			(end -0.12065 0.3048)
			(stroke
				(width 0.1)
				(type default)
			)
			(layer "F.Fab")
		)
		(fp_line
			(start -0.12065 -0.2794)
			(end 0.12065 -0.2794)
			(stroke
				(width 0.1)
				(type default)
			)
			(layer "F.Fab")
		)
		(fp_line
			(start -0.12065 -0.305054)
			(end -0.12065 -0.2794)
			(stroke
				(width 0.1)
				(type default)
			)
			(layer "F.Fab")
		)
		(fp_line
			(start -0.67945 0.3048)
			(end -0.67945 -0.305054)
			(stroke
				(width 0.1)
				(type default)
			)
			(layer "F.Fab")
		)
		(fp_line
			(start -0.67945 -0.305054)
			(end -0.12065 -0.305054)
			(stroke
				(width 0.1)
				(type default)
			)
			(layer "F.Fab")
		)
		(pad "1" smd circle
			(at -0.40005 0 180)
			(size 0 0)
			(layers "F.Cu" "F.Mask" "F.Paste")
			(net "P3V3_AUX")
		)
		(pad "2" smd circle
			(at 0.40005 0 180)
			(size 0 0)
			(layers "F.Cu" "F.Mask" "F.Paste")
			(net "PU_ESPI_ENABLE_STRAP")
		)
	)
)
